(kicad_pcb
	(version 20260206)
	(generator "pcbnew")
	(generator_version "10.0")
	(general
		(thickness 1.6)
		(legacy_teardrops no)
	)
	(paper "A4")
	(title_block
		(title "v1-tray-backplane — T6M_tray_BP_c_1023_1120.brd")
		(comment 1 "Open CloudServer (Microsoft) / footprint 72 of 170 (J9), pads 1-25 of 25")
	)
	(layers
		(0 "F.Cu" signal "TOP")
		(4 "In1.Cu" signal "GND")
		(6 "In2.Cu" signal "IN1")
		(8 "In3.Cu" signal "VCC")
		(10 "In4.Cu" signal "VCC1")
		(12 "In5.Cu" signal "IN2")
		(14 "In6.Cu" signal "GND1")
		(2 "B.Cu" signal "BOTTOM")
		(9 "F.Adhes" user "F.Adhesive")
		(11 "B.Adhes" user "B.Adhesive")
		(13 "F.Paste" user "Package Geometry/Pastemask Top")
		(15 "B.Paste" user "Package Geometry/Pastemask Bottom")
		(5 "F.SilkS" user "Ref Des/Silkscreen Top")
		(7 "B.SilkS" user "Ref Des/Silkscreen Bottom")
		(1 "F.Mask" user "Board Geometry/Soldermask Top")
		(3 "B.Mask" user "Board Geometry/Soldermask Bottom")
		(17 "Dwgs.User" user "User.Drawings")
		(19 "Cmts.User" user "User.Comments")
		(21 "Eco1.User" user "User.Eco1")
		(23 "Eco2.User" user "User.Eco2")
		(25 "Edge.Cuts" user "Board Geometry/Outline")
		(27 "Margin" user)
		(31 "F.CrtYd" user "Package Geometry/Place Bound Top")
		(29 "B.CrtYd" user "Package Geometry/Place Bound Bottom")
		(35 "F.Fab" user "Ref Des/Assembly Top")
		(33 "B.Fab" user "Ref Des/Assembly Bottom")
	)
	(footprint ""
		(layer "F.Cu")
		(at 306.319936 -14.999716)
		(property "Reference" "J9"
			(at -4.966208 -7.545832 0)
			(unlocked yes)
			(layer "F.SilkS")
			(effects
				(font
					(size 0.7874 0.5842)
					(thickness 0.1524)
				)
				(justify left)
			)
		)
		(property "Value" ""
			(at 0 0 0)
			(layer "F.Fab")
			(effects
				(font
					(size 1.27 1.27)
				)
			)
		)
		(duplicate_pad_numbers_are_jumpers no)
		(pad "" np_thru_hole circle
			(at 3.999992 5.500116)
			(size 2.159 2.159)
			(drill 2.159)
			(layers "*.Cu" "*.Mask")
			(clearance 0.381)
			(thermal_gap 0.381)
		)
		(pad "A1" thru_hole rect
			(at 0 0)
			(size 1.1684 1.1684)
			(drill 0.762)
			(layers "*.Cu" "*.Mask")
			(remove_unused_layers no)
			(net "GND")
			(clearance 0.0508)
			(thermal_gap 0.0508)
			(padstack
				(mode front_inner_back)
				(layer "Inner"
					(shape circle)
					(size 1.1684 1.1684)
					(clearance 0.0508)
				)
				(layer "B.Cu"
					(shape rect)
					(size 1.1684 1.1684)
					(clearance 0.0508)
				)
			)
		)
		(pad "A2" thru_hole circle
			(at 0 1.999996)
			(size 1.1684 1.1684)
			(drill 0.762)
			(layers "*.Cu" "*.Mask")
			(remove_unused_layers no)
			(net "GND")
			(clearance 0.0508)
			(thermal_gap 0.0508)
		)
		(pad "A3" thru_hole circle
			(at 0 3.999992)
			(size 1.1684 1.1684)
			(drill 0.762)
			(layers "*.Cu" "*.Mask")
			(remove_unused_layers no)
			(net "GND")
			(clearance 0.0508)
			(thermal_gap 0.0508)
		)
		(pad "A4" thru_hole circle
			(at 1.999996 0)
			(size 1.1684 1.1684)
			(drill 0.762)
			(layers "*.Cu" "*.Mask")
			(remove_unused_layers no)
			(net "GND")
			(clearance 0.0508)
			(thermal_gap 0.0508)
		)
		(pad "A5" thru_hole circle
			(at 1.999996 1.999996)
			(size 1.1684 1.1684)
			(drill 0.762)
			(layers "*.Cu" "*.Mask")
			(remove_unused_layers no)
			(net "GND")
			(clearance 0.0508)
			(thermal_gap 0.0508)
		)
		(pad "A6" thru_hole circle
			(at 1.999996 3.999992)
			(size 1.1684 1.1684)
			(drill 0.762)
			(layers "*.Cu" "*.Mask")
			(remove_unused_layers no)
			(net "GND")
			(clearance 0.0508)
			(thermal_gap 0.0508)
		)
		(pad "B1" thru_hole circle
			(at 7.999984 0)
			(size 1.1684 1.1684)
			(drill 0.762)
			(layers "*.Cu" "*.Mask")
			(remove_unused_layers no)
			(net "P12V")
			(clearance 0.0508)
			(thermal_gap 0.0508)
		)
		(pad "B2" thru_hole circle
			(at 7.999984 1.999996)
			(size 1.1684 1.1684)
			(drill 0.762)
			(layers "*.Cu" "*.Mask")
			(remove_unused_layers no)
			(net "P12V")
			(clearance 0.0508)
			(thermal_gap 0.0508)
		)
		(pad "B3" thru_hole circle
			(at 7.999984 3.999992)
			(size 1.1684 1.1684)
			(drill 0.762)
			(layers "*.Cu" "*.Mask")
			(remove_unused_layers no)
			(net "P12V")
			(clearance 0.0508)
			(thermal_gap 0.0508)
		)
		(pad "B4" thru_hole circle
			(at 5.999988 0)
			(size 1.1684 1.1684)
			(drill 0.762)
			(layers "*.Cu" "*.Mask")
			(remove_unused_layers no)
			(net "P12V")
			(clearance 0.0508)
			(thermal_gap 0.0508)
		)
		(pad "B5" thru_hole circle
			(at 5.999988 1.999996)
			(size 1.1684 1.1684)
			(drill 0.762)
			(layers "*.Cu" "*.Mask")
			(remove_unused_layers no)
			(net "P12V")
			(clearance 0.0508)
			(thermal_gap 0.0508)
		)
		(pad "B6" thru_hole circle
			(at 5.999988 3.999992)
			(size 1.1684 1.1684)
			(drill 0.762)
			(layers "*.Cu" "*.Mask")
			(remove_unused_layers no)
			(net "P12V")
			(clearance 0.0508)
			(thermal_gap 0.0508)
		)
		(pad "C1" thru_hole circle
			(at 7.999984 7.999984)
			(size 1.1684 1.1684)
			(drill 0.762)
			(layers "*.Cu" "*.Mask")
			(remove_unused_layers no)
			(net "P12V")
			(clearance 0.0508)
			(thermal_gap 0.0508)
		)
		(pad "C2" thru_hole circle
			(at 7.999984 9.99998)
			(size 1.1684 1.1684)
			(drill 0.762)
			(layers "*.Cu" "*.Mask")
			(remove_unused_layers no)
			(net "P12V")
			(clearance 0.0508)
			(thermal_gap 0.0508)
		)
		(pad "C3" thru_hole circle
			(at 7.999984 11.999976)
			(size 1.1684 1.1684)
			(drill 0.762)
			(layers "*.Cu" "*.Mask")
			(remove_unused_layers no)
			(net "P12V")
			(clearance 0.0508)
			(thermal_gap 0.0508)
		)
		(pad "C4" thru_hole circle
			(at 5.999988 7.999984)
			(size 1.1684 1.1684)
			(drill 0.762)
			(layers "*.Cu" "*.Mask")
			(remove_unused_layers no)
			(net "P12V")
			(clearance 0.0508)
			(thermal_gap 0.0508)
		)
		(pad "C5" thru_hole circle
			(at 5.999988 9.99998)
			(size 1.1684 1.1684)
			(drill 0.762)
			(layers "*.Cu" "*.Mask")
			(remove_unused_layers no)
			(net "P12V")
			(clearance 0.0508)
			(thermal_gap 0.0508)
		)
		(pad "C6" thru_hole circle
			(at 5.999988 11.999976)
			(size 1.1684 1.1684)
			(drill 0.762)
			(layers "*.Cu" "*.Mask")
			(remove_unused_layers no)
			(net "P12V")
			(clearance 0.0508)
			(thermal_gap 0.0508)
		)
		(pad "D1" thru_hole circle
			(at 0 7.999984)
			(size 1.1684 1.1684)
			(drill 0.762)
			(layers "*.Cu" "*.Mask")
			(remove_unused_layers no)
			(net "GND")
			(clearance 0.0508)
			(thermal_gap 0.0508)
		)
		(pad "D2" thru_hole circle
			(at 0 9.99998)
			(size 1.1684 1.1684)
			(drill 0.762)
			(layers "*.Cu" "*.Mask")
			(remove_unused_layers no)
			(net "GND")
			(clearance 0.0508)
			(thermal_gap 0.0508)
		)
		(pad "D3" thru_hole circle
			(at 0 11.999976)
			(size 1.1684 1.1684)
			(drill 0.762)
			(layers "*.Cu" "*.Mask")
			(remove_unused_layers no)
			(net "GND")
			(clearance 0.0508)
			(thermal_gap 0.0508)
		)
		(pad "D4" thru_hole circle
			(at 1.999996 7.999984)
			(size 1.1684 1.1684)
			(drill 0.762)
			(layers "*.Cu" "*.Mask")
			(remove_unused_layers no)
			(net "GND")
			(clearance 0.0508)
			(thermal_gap 0.0508)
		)
		(pad "D5" thru_hole circle
			(at 1.999996 9.99998)
			(size 1.1684 1.1684)
			(drill 0.762)
			(layers "*.Cu" "*.Mask")
			(remove_unused_layers no)
			(net "GND")
			(clearance 0.0508)
			(thermal_gap 0.0508)
		)
		(pad "D6" thru_hole circle
			(at 1.999996 11.999976)
			(size 1.1684 1.1684)
			(drill 0.762)
			(layers "*.Cu" "*.Mask")
			(remove_unused_layers no)
			(net "GND")
			(clearance 0.0508)
			(thermal_gap 0.0508)
		)
	)
)
